(kicad_pcb
	(version 20260206)
	(generator "pcbnew")
	(generator_version "10.0")
	(general
		(thickness 1.6)
		(legacy_teardrops no)
	)
	(paper "A4")
	(title_block
		(title "04192023_DAF0TMB3IC0_F0TG_MB_C_brd_V02_OCP.brd")
		(comment 1 "Grand Teton / footprints 7669-7676 of 8354")
	)
	(layers
		(0 "F.Cu" signal "TOP")
		(4 "In1.Cu" signal "GND")
		(6 "In2.Cu" signal "IN1")
		(8 "In3.Cu" signal "GND1")
		(10 "In4.Cu" signal "IN2")
		(12 "In5.Cu" signal "GND2")
		(14 "In6.Cu" signal "IN3")
		(16 "In7.Cu" signal "GND3")
		(18 "In8.Cu" signal "VCC")
		(20 "In9.Cu" signal "VCC1")
		(22 "In10.Cu" signal "GND4")
		(24 "In11.Cu" signal "IN4")
		(26 "In12.Cu" signal "GND5")
		(28 "In13.Cu" signal "IN5")
		(30 "In14.Cu" signal "GND6")
		(32 "In15.Cu" signal "IN6")
		(34 "In16.Cu" signal "GND7")
		(2 "B.Cu" signal "BOTTOM")
		(9 "F.Adhes" user "F.Adhesive")
		(11 "B.Adhes" user "B.Adhesive")
		(13 "F.Paste" user "Package Geometry/Pastemask Top")
		(15 "B.Paste" user "Package Geometry/Pastemask Bottom")
		(5 "F.SilkS" user "Ref Des/Silkscreen Top")
		(7 "B.SilkS" user "Ref Des/Silkscreen Bottom")
		(1 "F.Mask" user "Board Geometry/Soldermask Top")
		(3 "B.Mask" user "Board Geometry/Soldermask Bottom")
		(17 "Dwgs.User" user "User.Drawings")
		(19 "Cmts.User" user "User.Comments")
		(21 "Eco1.User" user "User.Eco1")
		(23 "Eco2.User" user "User.Eco2")
		(25 "Edge.Cuts" user "Board Geometry/Outline")
		(27 "Margin" user)
		(31 "F.CrtYd" user "Package Geometry/Place Bound Top")
		(29 "B.CrtYd" user "Package Geometry/Place Bound Bottom")
		(35 "F.Fab" user "Ref Des/Assembly Top")
		(33 "B.Fab" user "Ref Des/Assembly Bottom")
	)
	(footprint ""
		(layer "B.Cu")
		(at 365.328454 -251.78131)
		(property "Reference" "C2541"
			(at 0 0 0)
			(layer "B.SilkS")
			(hide yes)
			(effects
				(font
					(size 1.27 1.27)
				)
				(justify mirror)
			)
		)
		(property "Value" ""
			(at 0 0 0)
			(layer "B.Fab")
			(effects
				(font
					(size 1.27 1.27)
				)
				(justify mirror)
			)
		)
		(duplicate_pad_numbers_are_jumpers no)
		(fp_line
			(start -0.7874 -0.4064)
			(end -0.7874 0.4064)
			(stroke
				(width 0.1524)
				(type default)
			)
			(layer "B.SilkS")
		)
		(fp_line
			(start -0.7874 0.4064)
			(end 0.7874 0.4064)
			(stroke
				(width 0.1524)
				(type default)
			)
			(layer "B.SilkS")
		)
		(fp_line
			(start 0.7874 -0.4064)
			(end -0.7874 -0.4064)
			(stroke
				(width 0.1524)
				(type default)
			)
			(layer "B.SilkS")
		)
		(fp_line
			(start 0.7874 0.4064)
			(end 0.7874 -0.4064)
			(stroke
				(width 0.1524)
				(type default)
			)
			(layer "B.SilkS")
		)
		(fp_line
			(start -0.67945 -0.3048)
			(end -0.67945 0.3048)
			(stroke
				(width 0.1)
				(type default)
			)
			(layer "B.Fab")
		)
		(fp_line
			(start -0.67945 0.3048)
			(end -0.120396 0.3048)
			(stroke
				(width 0.1)
				(type default)
			)
			(layer "B.Fab")
		)
		(fp_line
			(start -0.12065 -0.3048)
			(end -0.67945 -0.3048)
			(stroke
				(width 0.1)
				(type default)
			)
			(layer "B.Fab")
		)
		(fp_line
			(start -0.12065 -0.2794)
			(end -0.12065 -0.3048)
			(stroke
				(width 0.1)
				(type default)
			)
			(layer "B.Fab")
		)
		(fp_line
			(start -0.120396 0.2794)
			(end 0.12065 0.2794)
			(stroke
				(width 0.1)
				(type default)
			)
			(layer "B.Fab")
		)
		(fp_line
			(start -0.120396 0.3048)
			(end -0.120396 0.2794)
			(stroke
				(width 0.1)
				(type default)
			)
			(layer "B.Fab")
		)
		(fp_line
			(start 0.12065 -0.305054)
			(end 0.12065 -0.2794)
			(stroke
				(width 0.1)
				(type default)
			)
			(layer "B.Fab")
		)
		(fp_line
			(start 0.12065 -0.2794)
			(end -0.12065 -0.2794)
			(stroke
				(width 0.1)
				(type default)
			)
			(layer "B.Fab")
		)
		(fp_line
			(start 0.12065 0.2794)
			(end 0.12065 0.3048)
			(stroke
				(width 0.1)
				(type default)
			)
			(layer "B.Fab")
		)
		(fp_line
			(start 0.12065 0.3048)
			(end 0.67945 0.3048)
			(stroke
				(width 0.1)
				(type default)
			)
			(layer "B.Fab")
		)
		(fp_line
			(start 0.67945 -0.305054)
			(end 0.12065 -0.305054)
			(stroke
				(width 0.1)
				(type default)
			)
			(layer "B.Fab")
		)
		(fp_line
			(start 0.67945 0.3048)
			(end 0.67945 -0.305054)
			(stroke
				(width 0.1)
				(type default)
			)
			(layer "B.Fab")
		)
		(pad "1" smd circle
			(at 0.40005 0 180)
			(size 0 0)
			(layers "B.Cu" "B.Mask" "B.Paste")
			(net "PVDDCR_SOC_P0")
		)
		(pad "2" smd circle
			(at -0.40005 0 180)
			(size 0 0)
			(layers "B.Cu" "B.Mask" "B.Paste")
			(net "GND")
		)
	)
	(footprint ""
		(layer "B.Cu")
		(at 74.720704 -408.517344 90)
		(property "Reference" "C6677"
			(at 0 0 90)
			(layer "B.SilkS")
			(hide yes)
			(effects
				(font
					(size 1.27 1.27)
				)
				(justify mirror)
			)
		)
		(property "Value" ""
			(at 0 0 90)
			(layer "B.Fab")
			(effects
				(font
					(size 1.27 1.27)
				)
				(justify mirror)
			)
		)
		(duplicate_pad_numbers_are_jumpers no)
		(fp_line
			(start 0.299974 -0.150114)
			(end -0.299974 -0.150114)
			(stroke
				(width 0.1)
				(type default)
			)
			(layer "B.Fab")
		)
		(fp_line
			(start -0.299974 -0.150114)
			(end -0.299974 0.150114)
			(stroke
				(width 0.1)
				(type default)
			)
			(layer "B.Fab")
		)
		(fp_line
			(start 0.299974 0.150114)
			(end 0.299974 -0.150114)
			(stroke
				(width 0.1)
				(type default)
			)
			(layer "B.Fab")
		)
		(fp_line
			(start -0.299974 0.150114)
			(end 0.299974 0.150114)
			(stroke
				(width 0.1)
				(type default)
			)
			(layer "B.Fab")
		)
		(pad "1" smd rect
			(at 0.2667 0 270)
			(size 0.3048 0.381)
			(layers "B.Cu" "B.Mask" "B.Paste")
			(net "P5E_CPU1_P1_TX_BUF_C_DP<8>")
		)
		(pad "2" smd rect
			(at -0.2667 0 270)
			(size 0.3048 0.381)
			(layers "B.Cu" "B.Mask" "B.Paste")
			(net "P5E_CPU1_P1_TX_BUF_DP<8>")
		)
	)
	(footprint ""
		(layer "B.Cu")
		(at 318.43726 -328.240644 -90)
		(property "Reference" "PC97"
			(at 9.490456 -0.314706 270)
			(unlocked yes)
			(layer "B.SilkS")
			(effects
				(font
					(size 0.7874 0.5842)
					(thickness 0.1524)
				)
				(justify left mirror)
			)
		)
		(property "Value" ""
			(at 0 0 90)
			(layer "B.Fab")
			(effects
				(font
					(size 1.27 1.27)
				)
				(justify mirror)
			)
		)
		(duplicate_pad_numbers_are_jumpers no)
		(fp_line
			(start -4.533392 2.249932)
			(end 4.533392 2.249932)
			(stroke
				(width 0.1524)
				(type default)
			)
			(layer "B.SilkS")
		)
		(fp_line
			(start 4.533392 2.249932)
			(end 4.533392 -2.249932)
			(stroke
				(width 0.1524)
				(type default)
			)
			(layer "B.SilkS")
		)
		(fp_line
			(start -4.533392 -2.249932)
			(end -4.533392 2.249932)
			(stroke
				(width 0.1524)
				(type default)
			)
			(layer "B.SilkS")
		)
		(fp_line
			(start 4.533392 -2.249932)
			(end -4.533392 -2.249932)
			(stroke
				(width 0.1524)
				(type default)
			)
			(layer "B.SilkS")
		)
		(fp_rect
			(start 5.39242 2.326132)
			(end 4.533392 -2.326132)
			(stroke
				(width 0)
				(type default)
			)
			(fill yes)
			(layer "B.SilkS")
		)
		(fp_line
			(start -3.750056 2.249932)
			(end 3.750056 2.249932)
			(stroke
				(width 0.1)
				(type default)
			)
			(layer "B.Fab")
		)
		(fp_line
			(start 3.750056 2.249932)
			(end 3.750056 -2.249932)
			(stroke
				(width 0.1)
				(type default)
			)
			(layer "B.Fab")
		)
		(fp_line
			(start -3.750056 -2.249932)
			(end -3.750056 2.249932)
			(stroke
				(width 0.1)
				(type default)
			)
			(layer "B.Fab")
		)
		(fp_line
			(start 3.750056 -2.249932)
			(end -3.750056 -2.249932)
			(stroke
				(width 0.1)
				(type default)
			)
			(layer "B.Fab")
		)
		(fp_text user "-"
			(at -4.77012 2.405634 270)
			(unlocked yes)
			(layer "B.SilkS")
			(effects
				(font
					(size 1.905 1.4224)
					(thickness 0.1524)
				)
				(justify left mirror)
			)
		)
		(fp_text user "+"
			(at 6.322314 0.786384 180)
			(unlocked yes)
			(layer "B.SilkS")
			(effects
				(font
					(size 1.905 1.4224)
					(thickness 0.1524)
				)
				(justify left mirror)
			)
		)
		(fp_text user "+"
			(at 6.322314 0.786384 180)
			(unlocked yes)
			(layer "B.Fab")
			(effects
				(font
					(size 1.905 1.4224)
					(thickness 0.1524)
				)
				(justify left mirror)
			)
		)
		(fp_text user "-"
			(at -4.8514 -0.14605 270)
			(unlocked yes)
			(layer "B.Fab")
			(effects
				(font
					(size 1.905 1.4224)
					(thickness 0.1524)
				)
				(justify left mirror)
			)
		)
		(pad "1" smd rect
			(at 3.199892 0 90)
			(size 2.413 2.8194)
			(layers "B.Cu" "B.Mask" "B.Paste")
			(net "PVDDCR_CPU1_P0")
		)
		(pad "2" smd rect
			(at -3.199892 0 90)
			(size 2.413 2.8194)
			(layers "B.Cu" "B.Mask" "B.Paste")
			(net "GND")
		)
	)
	(footprint ""
		(layer "B.Cu")
		(at 206.429356 -377.666504 180)
		(property "Reference" "PR2520"
			(at 0 0 0)
			(layer "B.SilkS")
			(hide yes)
			(effects
				(font
					(size 1.27 1.27)
				)
				(justify mirror)
			)
		)
		(property "Value" ""
			(at 0 0 0)
			(layer "B.Fab")
			(effects
				(font
					(size 1.27 1.27)
				)
				(justify mirror)
			)
		)
		(duplicate_pad_numbers_are_jumpers no)
		(fp_line
			(start 0.7874 0.4064)
			(end 0.7874 -0.4064)
			(stroke
				(width 0.1524)
				(type default)
			)
			(layer "B.SilkS")
		)
		(fp_line
			(start 0.7874 -0.4064)
			(end -0.7874 -0.4064)
			(stroke
				(width 0.1524)
				(type default)
			)
			(layer "B.SilkS")
		)
		(fp_line
			(start -0.7874 0.4064)
			(end 0.7874 0.4064)
			(stroke
				(width 0.1524)
				(type default)
			)
			(layer "B.SilkS")
		)
		(fp_line
			(start -0.7874 -0.4064)
			(end -0.7874 0.4064)
			(stroke
				(width 0.1524)
				(type default)
			)
			(layer "B.SilkS")
		)
		(fp_line
			(start 0.67945 0.3048)
			(end 0.67945 -0.305054)
			(stroke
				(width 0.1)
				(type default)
			)
			(layer "B.Fab")
		)
		(fp_line
			(start 0.67945 -0.305054)
			(end 0.12065 -0.305054)
			(stroke
				(width 0.1)
				(type default)
			)
			(layer "B.Fab")
		)
		(fp_line
			(start 0.12065 0.3048)
			(end 0.67945 0.3048)
			(stroke
				(width 0.1)
				(type default)
			)
			(layer "B.Fab")
		)
		(fp_line
			(start 0.12065 0.2794)
			(end 0.12065 0.3048)
			(stroke
				(width 0.1)
				(type default)
			)
			(layer "B.Fab")
		)
		(fp_line
			(start 0.12065 -0.2794)
			(end -0.12065 -0.2794)
			(stroke
				(width 0.1)
				(type default)
			)
			(layer "B.Fab")
		)
		(fp_line
			(start 0.12065 -0.305054)
			(end 0.12065 -0.2794)
			(stroke
				(width 0.1)
				(type default)
			)
			(layer "B.Fab")
		)
		(fp_line
			(start -0.120396 0.3048)
			(end -0.120396 0.2794)
			(stroke
				(width 0.1)
				(type default)
			)
			(layer "B.Fab")
		)
		(fp_line
			(start -0.120396 0.2794)
			(end 0.12065 0.2794)
			(stroke
				(width 0.1)
				(type default)
			)
			(layer "B.Fab")
		)
		(fp_line
			(start -0.12065 -0.2794)
			(end -0.12065 -0.3048)
			(stroke
				(width 0.1)
				(type default)
			)
			(layer "B.Fab")
		)
		(fp_line
			(start -0.12065 -0.3048)
			(end -0.67945 -0.3048)
			(stroke
				(width 0.1)
				(type default)
			)
			(layer "B.Fab")
		)
		(fp_line
			(start -0.67945 0.3048)
			(end -0.120396 0.3048)
			(stroke
				(width 0.1)
				(type default)
			)
			(layer "B.Fab")
		)
		(fp_line
			(start -0.67945 -0.3048)
			(end -0.67945 0.3048)
			(stroke
				(width 0.1)
				(type default)
			)
			(layer "B.Fab")
		)
		(pad "1" smd circle
			(at 0.40005 0)
			(size 0 0)
			(layers "B.Cu" "B.Mask" "B.Paste")
			(net "P12V_HSC_SENSE2_P")
		)
		(pad "2" smd circle
			(at -0.40005 0)
			(size 0 0)
			(layers "B.Cu" "B.Mask" "B.Paste")
			(net "P12V_HSC_SENSE2_R1_P")
		)
	)
	(footprint ""
		(layer "B.Cu")
		(at 439.020966 -420.231824 180)
		(property "Reference" "R6801"
			(at 0 0 0)
			(layer "B.SilkS")
			(hide yes)
			(effects
				(font
					(size 1.27 1.27)
				)
				(justify mirror)
			)
		)
		(property "Value" ""
			(at 0 0 0)
			(layer "B.Fab")
			(effects
				(font
					(size 1.27 1.27)
				)
				(justify mirror)
			)
		)
		(duplicate_pad_numbers_are_jumpers no)
		(fp_line
			(start 0.7874 0.4064)
			(end 0.7874 -0.4064)
			(stroke
				(width 0.1524)
				(type default)
			)
			(layer "B.SilkS")
		)
		(fp_line
			(start 0.7874 -0.4064)
			(end -0.7874 -0.4064)
			(stroke
				(width 0.1524)
				(type default)
			)
			(layer "B.SilkS")
		)
		(fp_line
			(start -0.7874 0.4064)
			(end 0.7874 0.4064)
			(stroke
				(width 0.1524)
				(type default)
			)
			(layer "B.SilkS")
		)
		(fp_line
			(start -0.7874 -0.4064)
			(end -0.7874 0.4064)
			(stroke
				(width 0.1524)
				(type default)
			)
			(layer "B.SilkS")
		)
		(fp_line
			(start 0.67945 0.3048)
			(end 0.67945 -0.305054)
			(stroke
				(width 0.1)
				(type default)
			)
			(layer "B.Fab")
		)
		(fp_line
			(start 0.67945 -0.305054)
			(end 0.12065 -0.305054)
			(stroke
				(width 0.1)
				(type default)
			)
			(layer "B.Fab")
		)
		(fp_line
			(start 0.12065 0.3048)
			(end 0.67945 0.3048)
			(stroke
				(width 0.1)
				(type default)
			)
			(layer "B.Fab")
		)
		(fp_line
			(start 0.12065 0.2794)
			(end 0.12065 0.3048)
			(stroke
				(width 0.1)
				(type default)
			)
			(layer "B.Fab")
		)
		(fp_line
			(start 0.12065 -0.2794)
			(end -0.12065 -0.2794)
			(stroke
				(width 0.1)
				(type default)
			)
			(layer "B.Fab")
		)
		(fp_line
			(start 0.12065 -0.305054)
			(end 0.12065 -0.2794)
			(stroke
				(width 0.1)
				(type default)
			)
			(layer "B.Fab")
		)
		(fp_line
			(start -0.120396 0.3048)
			(end -0.120396 0.2794)
			(stroke
				(width 0.1)
				(type default)
			)
			(layer "B.Fab")
		)
		(fp_line
			(start -0.120396 0.2794)
			(end 0.12065 0.2794)
			(stroke
				(width 0.1)
				(type default)
			)
			(layer "B.Fab")
		)
		(fp_line
			(start -0.12065 -0.2794)
			(end -0.12065 -0.3048)
			(stroke
				(width 0.1)
				(type default)
			)
			(layer "B.Fab")
		)
		(fp_line
			(start -0.12065 -0.3048)
			(end -0.67945 -0.3048)
			(stroke
				(width 0.1)
				(type default)
			)
			(layer "B.Fab")
		)
		(fp_line
			(start -0.67945 0.3048)
			(end -0.120396 0.3048)
			(stroke
				(width 0.1)
				(type default)
			)
			(layer "B.Fab")
		)
		(fp_line
			(start -0.67945 -0.3048)
			(end -0.67945 0.3048)
			(stroke
				(width 0.1)
				(type default)
			)
			(layer "B.Fab")
		)
		(pad "1" smd circle
			(at 0.40005 0)
			(size 0 0)
			(layers "B.Cu" "B.Mask" "B.Paste")
			(net "GND")
		)
		(pad "2" smd circle
			(at -0.40005 0)
			(size 0 0)
			(layers "B.Cu" "B.Mask" "B.Paste")
			(net "P0V9_RETIMER_CPU0_EN1_R")
		)
	)
	(footprint ""
		(layer "B.Cu")
		(at 90.37193 -335.04632 90)
		(property "Reference" "PC384_1"
			(at 0 0 90)
			(layer "B.SilkS")
			(hide yes)
			(effects
				(font
					(size 1.27 1.27)
				)
				(justify mirror)
			)
		)
		(property "Value" ""
			(at 0 0 90)
			(layer "B.Fab")
			(effects
				(font
					(size 1.27 1.27)
				)
				(justify mirror)
			)
		)
		(duplicate_pad_numbers_are_jumpers no)
		(fp_line
			(start 1.524 -0.762)
			(end -1.524 -0.762)
			(stroke
				(width 0.1524)
				(type default)
			)
			(layer "B.SilkS")
		)
		(fp_line
			(start -1.524 -0.762)
			(end -1.524 0.762)
			(stroke
				(width 0.1524)
				(type default)
			)
			(layer "B.SilkS")
		)
		(fp_line
			(start 1.524 0.762)
			(end 1.524 -0.762)
			(stroke
				(width 0.1524)
				(type default)
			)
			(layer "B.SilkS")
		)
		(fp_line
			(start -1.524 0.762)
			(end 1.524 0.762)
			(stroke
				(width 0.1524)
				(type default)
			)
			(layer "B.SilkS")
		)
		(fp_line
			(start 1.1049 -0.724916)
			(end 1.1049 0.724916)
			(stroke
				(width 0.1)
				(type default)
			)
			(layer "B.Fab")
		)
		(fp_line
			(start -1.1049 -0.724916)
			(end 1.1049 -0.724916)
			(stroke
				(width 0.1)
				(type default)
			)
			(layer "B.Fab")
		)
		(fp_line
			(start 1.1049 0.724916)
			(end -1.1049 0.724916)
			(stroke
				(width 0.1)
				(type default)
			)
			(layer "B.Fab")
		)
		(fp_line
			(start -1.1049 0.724916)
			(end -1.1049 -0.724916)
			(stroke
				(width 0.1)
				(type default)
			)
			(layer "B.Fab")
		)
		(pad "1" smd rect
			(at 0.889 0 90)
			(size 1.016 1.27)
			(layers "B.Cu" "B.Mask" "B.Paste")
			(net "SW_P12V_AUX_PVDDCR_CPU1_P1_FLT")
		)
		(pad "2" smd rect
			(at -0.889 0 90)
			(size 1.016 1.27)
			(layers "B.Cu" "B.Mask" "B.Paste")
			(net "GND")
		)
	)
	(footprint ""
		(layer "B.Cu")
		(at 303.378362 -395.148562 90)
		(property "Reference" "C521"
			(at 0 0 90)
			(layer "B.SilkS")
			(hide yes)
			(effects
				(font
					(size 1.27 1.27)
				)
				(justify mirror)
			)
		)
		(property "Value" ""
			(at 0 0 90)
			(layer "B.Fab")
			(effects
				(font
					(size 1.27 1.27)
				)
				(justify mirror)
			)
		)
		(duplicate_pad_numbers_are_jumpers no)
		(fp_line
			(start 0.299974 -0.150114)
			(end -0.299974 -0.150114)
			(stroke
				(width 0.1)
				(type default)
			)
			(layer "B.Fab")
		)
		(fp_line
			(start -0.299974 -0.150114)
			(end -0.299974 0.150114)
			(stroke
				(width 0.1)
				(type default)
			)
			(layer "B.Fab")
		)
		(fp_line
			(start 0.299974 0.150114)
			(end 0.299974 -0.150114)
			(stroke
				(width 0.1)
				(type default)
			)
			(layer "B.Fab")
		)
		(fp_line
			(start -0.299974 0.150114)
			(end 0.299974 0.150114)
			(stroke
				(width 0.1)
				(type default)
			)
			(layer "B.Fab")
		)
		(pad "1" smd rect
			(at 0.2667 0 270)
			(size 0.3048 0.381)
			(layers "B.Cu" "B.Mask" "B.Paste")
			(net "P0V9_CPU0_RT0_2A")
		)
		(pad "2" smd rect
			(at -0.2667 0 270)
			(size 0.3048 0.381)
			(layers "B.Cu" "B.Mask" "B.Paste")
			(net "GND")
		)
	)
	(footprint ""
		(layer "B.Cu")
		(at 128.891284 -390.560052 90)
		(property "Reference" "C499"
			(at 0 0 90)
			(layer "B.SilkS")
			(hide yes)
			(effects
				(font
					(size 1.27 1.27)
				)
				(justify mirror)
			)
		)
		(property "Value" ""
			(at 0 0 90)
			(layer "B.Fab")
			(effects
				(font
					(size 1.27 1.27)
				)
				(justify mirror)
			)
		)
		(duplicate_pad_numbers_are_jumpers no)
		(fp_line
			(start 0.7874 -0.4064)
			(end -0.7874 -0.4064)
			(stroke
				(width 0.1524)
				(type default)
			)
			(layer "B.SilkS")
		)
		(fp_line
			(start -0.7874 -0.4064)
			(end -0.7874 0.4064)
			(stroke
				(width 0.1524)
				(type default)
			)
			(layer "B.SilkS")
		)
		(fp_line
			(start 0.7874 0.4064)
			(end 0.7874 -0.4064)
			(stroke
				(width 0.1524)
				(type default)
			)
			(layer "B.SilkS")
		)
		(fp_line
			(start -0.7874 0.4064)
			(end 0.7874 0.4064)
			(stroke
				(width 0.1524)
				(type default)
			)
			(layer "B.SilkS")
		)
		(fp_line
			(start 0.67945 -0.305054)
			(end 0.12065 -0.305054)
			(stroke
				(width 0.1)
				(type default)
			)
			(layer "B.Fab")
		)
		(fp_line
			(start 0.12065 -0.305054)
			(end 0.12065 -0.2794)
			(stroke
				(width 0.1)
				(type default)
			)
			(layer "B.Fab")
		)
		(fp_line
			(start -0.12065 -0.3048)
			(end -0.67945 -0.3048)
			(stroke
				(width 0.1)
				(type default)
			)
			(layer "B.Fab")
		)
		(fp_line
			(start -0.67945 -0.3048)
			(end -0.67945 0.3048)
			(stroke
				(width 0.1)
				(type default)
			)
			(layer "B.Fab")
		)
		(fp_line
			(start 0.12065 -0.2794)
			(end -0.12065 -0.2794)
			(stroke
				(width 0.1)
				(type default)
			)
			(layer "B.Fab")
		)
		(fp_line
			(start -0.12065 -0.2794)
			(end -0.12065 -0.3048)
			(stroke
				(width 0.1)
				(type default)
			)
			(layer "B.Fab")
		)
		(fp_line
			(start 0.12065 0.2794)
			(end 0.12065 0.3048)
			(stroke
				(width 0.1)
				(type default)
			)
			(layer "B.Fab")
		)
		(fp_line
			(start -0.120396 0.2794)
			(end 0.12065 0.2794)
			(stroke
				(width 0.1)
				(type default)
			)
			(layer "B.Fab")
		)
		(fp_line
			(start 0.67945 0.3048)
			(end 0.67945 -0.305054)
			(stroke
				(width 0.1)
				(type default)
			)
			(layer "B.Fab")
		)
		(fp_line
			(start 0.12065 0.3048)
			(end 0.67945 0.3048)
			(stroke
				(width 0.1)
				(type default)
			)
			(layer "B.Fab")
		)
		(fp_line
			(start -0.120396 0.3048)
			(end -0.120396 0.2794)
			(stroke
				(width 0.1)
				(type default)
			)
			(layer "B.Fab")
		)
		(fp_line
			(start -0.67945 0.3048)
			(end -0.120396 0.3048)
			(stroke
				(width 0.1)
				(type default)
			)
			(layer "B.Fab")
		)
		(pad "1" smd circle
			(at 0.40005 0 270)
			(size 0 0)
			(layers "B.Cu" "B.Mask" "B.Paste")
			(net "P0V9_CPU1_RT3_2A")
		)
		(pad "2" smd circle
			(at -0.40005 0 270)
			(size 0 0)
			(layers "B.Cu" "B.Mask" "B.Paste")
			(net "GND")
		)
	)
)
